(kicad_pcb
	(version 20260206)
	(generator "pcbnew")
	(generator_version "10.0")
	(general
		(thickness 1.6)
		(legacy_teardrops no)
	)
	(paper "A4")
	(title_block
		(title "Bryce Canyon_IOM_M2_16342-2_OCP.brd")
		(comment 1 "Bryce Canyon / footprints 185-191 of 1146")
	)
	(layers
		(0 "F.Cu" signal "TOP")
		(4 "In1.Cu" signal "L2GND")
		(6 "In2.Cu" signal "L3")
		(8 "In3.Cu" signal "L4VCC")
		(10 "In4.Cu" signal "L5VCC")
		(12 "In5.Cu" signal "L6")
		(14 "In6.Cu" signal "L7GND")
		(2 "B.Cu" signal "BOTTOM")
		(9 "F.Adhes" user "F.Adhesive")
		(11 "B.Adhes" user "B.Adhesive")
		(13 "F.Paste" user "Package Geometry/Pastemask Top")
		(15 "B.Paste" user "Package Geometry/Pastemask Bottom")
		(5 "F.SilkS" user "Ref Des/Silkscreen Top")
		(7 "B.SilkS" user "Ref Des/Silkscreen Bottom")
		(1 "F.Mask" user "Board Geometry/Soldermask Top")
		(3 "B.Mask" user "Board Geometry/Soldermask Bottom")
		(17 "Dwgs.User" user "User.Drawings")
		(19 "Cmts.User" user "User.Comments")
		(21 "Eco1.User" user "User.Eco1")
		(23 "Eco2.User" user "User.Eco2")
		(25 "Edge.Cuts" user "Board Geometry/Outline")
		(27 "Margin" user)
		(31 "F.CrtYd" user "Package Geometry/Place Bound Top")
		(29 "B.CrtYd" user "Package Geometry/Place Bound Bottom")
		(35 "F.Fab" user "Ref Des/Assembly Top")
		(33 "B.Fab" user "Ref Des/Assembly Bottom")
	)
	(footprint ""
		(layer "F.Cu")
		(at 70.59803 -139.546076 90)
		(property "Reference" "U5"
			(at 0 0 90)
			(layer "F.SilkS")
			(hide yes)
			(effects
				(font
					(size 1.27 1.27)
				)
			)
		)
		(property "Value" "74LVC2G07GW-GP"
			(at -2.3622 -8.2042 90)
			(unlocked yes)
			(layer "F.Fab")
			(hide yes)
			(effects
				(font
					(size 1.016 1.016)
					(thickness 0.1524)
				)
			)
		)
		(property "Device Type" "SOT-363H44"
			(at -2.3622 -10.1092 90)
			(unlocked yes)
			(layer "F.Fab")
			(hide yes)
			(effects
				(font
					(size 1.016 1.016)
					(thickness 0.1524)
				)
			)
		)
		(duplicate_pad_numbers_are_jumpers no)
		(fp_line
			(start 1.4478 -1.7018)
			(end -1.4478 -1.7018)
			(stroke
				(width 0.1524)
				(type default)
			)
			(layer "F.SilkS")
		)
		(fp_line
			(start -1.4478 -1.7018)
			(end -1.4478 1.7018)
			(stroke
				(width 0.1524)
				(type default)
			)
			(layer "F.SilkS")
		)
		(fp_line
			(start -1.27 1.524)
			(end -1.27 0.6604)
			(stroke
				(width 0.4826)
				(type default)
			)
			(layer "F.SilkS")
		)
		(fp_line
			(start 1.4478 1.7018)
			(end 1.4478 -1.7018)
			(stroke
				(width 0.1524)
				(type default)
			)
			(layer "F.SilkS")
		)
		(fp_line
			(start -1.4478 1.7018)
			(end 1.4478 1.7018)
			(stroke
				(width 0.1524)
				(type default)
			)
			(layer "F.SilkS")
		)
		(fp_poly
			(pts
				(xy -1.524 -1.778) (xy 1.524 -1.778) (xy 1.524 1.778) (xy -1.524 1.778)
			)
			(stroke
				(width 0)
				(type default)
			)
			(fill no)
			(layer "F.CrtYd")
		)
		(fp_poly
			(pts
				(xy -1.524 -1.778) (xy 1.524 -1.778) (xy 1.524 1.778) (xy -1.524 1.778)
			)
			(stroke
				(width 0)
				(type default)
			)
			(fill no)
			(layer "F.Fab")
		)
		(pad "1" smd rect
			(at -0.65024 0.9398 90)
			(size 0.4064 1.016)
			(layers "F.Cu" "F.Mask" "F.Paste")
			(net "FP_PWR_BTN_N_R")
		)
		(pad "2" smd rect
			(at 0 0.9398 90)
			(size 0.4064 1.016)
			(layers "F.Cu" "F.Mask" "F.Paste")
			(net "GND")
		)
		(pad "3" smd rect
			(at 0.65024 0.9398 90)
			(size 0.4064 1.016)
			(layers "F.Cu" "F.Mask" "F.Paste")
			(net "FP_RESET_RC_N")
		)
		(pad "4" smd rect
			(at 0.65024 -0.9398 90)
			(size 0.4064 1.016)
			(layers "F.Cu" "F.Mask" "F.Paste")
			(net "FP_RETBTN")
		)
		(pad "5" smd rect
			(at 0 -0.9398 90)
			(size 0.4064 1.016)
			(layers "F.Cu" "F.Mask" "F.Paste")
			(net "P3V3_STBY")
		)
		(pad "6" smd rect
			(at -0.65024 -0.9398 90)
			(size 0.4064 1.016)
			(layers "F.Cu" "F.Mask" "F.Paste")
			(net "FP_PWRBTN")
		)
	)
	(footprint ""
		(layer "F.Cu")
		(at 165.619684 -132.507482 90)
		(property "Reference" "R804"
			(at 0 0 90)
			(layer "F.SilkS")
			(hide yes)
			(effects
				(font
					(size 1.27 1.27)
				)
			)
		)
		(property "Value" "4K7R2F-GP"
			(at 0.064008 -3.993896 90)
			(unlocked yes)
			(layer "F.Fab")
			(hide yes)
			(effects
				(font
					(size 1.016 1.016)
					(thickness 0.1524)
				)
			)
		)
		(property "Device Type" "R402H16"
			(at 0.064008 -5.517896 90)
			(unlocked yes)
			(layer "F.Fab")
			(hide yes)
			(effects
				(font
					(size 1.016 1.016)
					(thickness 0.1524)
				)
			)
		)
		(duplicate_pad_numbers_are_jumpers no)
		(fp_line
			(start 0.508 -0.9398)
			(end -0.508 -0.9398)
			(stroke
				(width 0.1524)
				(type default)
			)
			(layer "F.SilkS")
		)
		(fp_line
			(start -0.508 -0.9398)
			(end -0.508 0.9398)
			(stroke
				(width 0.1524)
				(type default)
			)
			(layer "F.SilkS")
		)
		(fp_rect
			(start -0.508 0.9398)
			(end 0.508 -0.9398)
			(stroke
				(width 0)
				(type default)
			)
			(fill no)
			(layer "F.CrtYd")
		)
		(fp_rect
			(start -0.508 0.9398)
			(end 0.508 -0.9398)
			(stroke
				(width 0)
				(type default)
			)
			(fill no)
			(layer "F.Fab")
		)
		(pad "1" smd custom
			(at 0 -0.4445 90)
			(size 0.1397 0.1397)
			(layers "F.Cu" "F.Mask" "F.Paste")
			(net "P3V3_STBY")
			(options
				(clearance outline)
				(anchor circle)
			)
			(primitives
				(gr_poly
					(pts
						(arc
							(start -0.1778 -0.2794)
							(mid -0.249642 -0.249642)
							(end -0.2794 -0.1778)
						)
						(arc
							(start -0.2794 0.1778)
							(mid -0.249642 0.249642)
							(end -0.1778 0.2794)
						)
						(arc
							(start 0.1778 0.2794)
							(mid 0.249642 0.249642)
							(end 0.2794 0.1778)
						)
						(arc
							(start 0.2794 -0.1778)
							(mid 0.249642 -0.249642)
							(end 0.1778 -0.2794)
						)
					)
					(width 0)
					(fill yes)
				)
			)
		)
		(pad "2" smd custom
			(at 0 0.4445 90)
			(size 0.1397 0.1397)
			(layers "F.Cu" "F.Mask" "F.Paste")
			(net "M2_2_PRESENT_N")
			(options
				(clearance outline)
				(anchor circle)
			)
			(primitives
				(gr_poly
					(pts
						(arc
							(start -0.1778 -0.2794)
							(mid -0.249642 -0.249642)
							(end -0.2794 -0.1778)
						)
						(arc
							(start -0.2794 0.1778)
							(mid -0.249642 0.249642)
							(end -0.1778 0.2794)
						)
						(arc
							(start 0.1778 0.2794)
							(mid 0.249642 0.249642)
							(end 0.2794 0.1778)
						)
						(arc
							(start 0.2794 -0.1778)
							(mid 0.249642 -0.249642)
							(end 0.1778 -0.2794)
						)
					)
					(width 0)
					(fill yes)
				)
			)
		)
	)
	(footprint ""
		(layer "F.Cu")
		(at 78.122018 -90.155268 90)
		(property "Reference" "VIA7"
			(at 0 0 90)
			(layer "F.SilkS")
			(hide yes)
			(effects
				(font
					(size 1.27 1.27)
				)
			)
		)
		(property "Value" "85OHM-8L-1D6MM-L16L18-GP"
			(at 4.064 0.6096 90)
			(unlocked yes)
			(layer "F.Fab")
			(hide yes)
			(effects
				(font
					(size 1.016 1.016)
					(thickness 0.1524)
				)
			)
		)
		(property "Device Type" "VIA-PCIE-4P-368076"
			(at 4.064 -0.9144 90)
			(unlocked yes)
			(layer "F.Fab")
			(hide yes)
			(effects
				(font
					(size 1.016 1.016)
					(thickness 0.1524)
				)
			)
		)
		(duplicate_pad_numbers_are_jumpers no)
		(fp_rect
			(start -1.8415 0.381)
			(end 1.8415 -0.381)
			(stroke
				(width 0)
				(type default)
			)
			(fill no)
			(layer "F.CrtYd")
		)
		(fp_rect
			(start -1.8415 0.381)
			(end 1.8415 -0.381)
			(stroke
				(width 0)
				(type default)
			)
			(fill no)
			(layer "F.Fab")
		)
		(pad "1" thru_hole circle
			(at -1.4605 0 90)
			(size 0.508 0.508)
			(drill 0.254)
			(layers "*.Cu" "*.Mask")
			(remove_unused_layers no)
			(net "GND")
			(clearance 0.127)
			(thermal_gap 0.127)
		)
		(pad "2" thru_hole circle
			(at -0.4445 0 90)
			(size 0.508 0.508)
			(drill 0.254)
			(layers "*.Cu" "*.Mask")
			(remove_unused_layers no)
			(net "PCIE_COMP_TO_IOM_22_DP")
			(clearance 0.127)
			(thermal_gap 0.127)
		)
		(pad "3" thru_hole circle
			(at 0.4445 0 90)
			(size 0.508 0.508)
			(drill 0.254)
			(layers "*.Cu" "*.Mask")
			(remove_unused_layers no)
			(net "PCIE_COMP_TO_IOM_22_DN")
			(clearance 0.127)
			(thermal_gap 0.127)
		)
		(pad "4" thru_hole circle
			(at 1.4605 0 90)
			(size 0.508 0.508)
			(drill 0.254)
			(layers "*.Cu" "*.Mask")
			(remove_unused_layers no)
			(net "GND")
			(clearance 0.127)
			(thermal_gap 0.127)
		)
	)
	(footprint ""
		(layer "F.Cu")
		(at 92.775786 -44.664376 90)
		(property "Reference" "PQ2"
			(at 0 0 90)
			(layer "F.SilkS")
			(hide yes)
			(effects
				(font
					(size 1.27 1.27)
				)
			)
		)
		(property "Value" "2N7002K-1-GP"
			(at 0.127 -8.9662 90)
			(unlocked yes)
			(layer "F.Fab")
			(hide yes)
			(effects
				(font
					(size 1.016 1.016)
					(thickness 0.1524)
				)
			)
		)
		(property "Device Type" "SOT23DGS2D4H44"
			(at 0.127 -10.4902 90)
			(unlocked yes)
			(layer "F.Fab")
			(hide yes)
			(effects
				(font
					(size 1.016 1.016)
					(thickness 0.1524)
				)
			)
		)
		(duplicate_pad_numbers_are_jumpers no)
		(fp_line
			(start 1.651 -1.778)
			(end -1.651 -1.778)
			(stroke
				(width 0.1524)
				(type default)
			)
			(layer "F.SilkS")
		)
		(fp_line
			(start -1.651 -1.778)
			(end -1.651 1.778)
			(stroke
				(width 0.1524)
				(type default)
			)
			(layer "F.SilkS")
		)
		(fp_line
			(start 1.651 1.778)
			(end 1.651 -1.778)
			(stroke
				(width 0.1524)
				(type default)
			)
			(layer "F.SilkS")
		)
		(fp_line
			(start -1.651 1.778)
			(end 1.651 1.778)
			(stroke
				(width 0.1524)
				(type default)
			)
			(layer "F.SilkS")
		)
		(fp_poly
			(pts
				(xy -1.778 1.8796) (xy -1.778 -1.8796) (xy 1.778 -1.8796) (xy 1.778 1.8796)
			)
			(stroke
				(width 0)
				(type default)
			)
			(fill no)
			(layer "F.CrtYd")
		)
		(fp_poly
			(pts
				(xy -1.778 1.8796) (xy -1.778 -1.8796) (xy 1.778 -1.8796) (xy 1.778 1.8796)
			)
			(stroke
				(width 0)
				(type default)
			)
			(fill no)
			(layer "F.Fab")
		)
		(pad "D" smd custom
			(at 0 -0.9525 90)
			(size 0.1905 0.1905)
			(layers "F.Cu" "F.Mask" "F.Paste")
			(net "PQ2_D")
			(options
				(clearance outline)
				(anchor circle)
			)
			(primitives
				(gr_poly
					(pts
						(arc
							(start -0.1778 0.5715)
							(mid -0.321484 0.511984)
							(end -0.381 0.3683)
						)
						(arc
							(start -0.381 -0.3683)
							(mid -0.321484 -0.511984)
							(end -0.1778 -0.5715)
						)
						(arc
							(start 0.1778 -0.5715)
							(mid 0.321484 -0.511984)
							(end 0.381 -0.3683)
						)
						(arc
							(start 0.381 0.3683)
							(mid 0.321484 0.511984)
							(end 0.1778 0.5715)
						)
					)
					(width 0)
					(fill yes)
				)
			)
		)
		(pad "G" smd custom
			(at -0.98425 0.9525 90)
			(size 0.1905 0.1905)
			(layers "F.Cu" "F.Mask" "F.Paste")
			(net "PQ2_G")
			(options
				(clearance outline)
				(anchor circle)
			)
			(primitives
				(gr_poly
					(pts
						(arc
							(start -0.1778 0.5715)
							(mid -0.321484 0.511984)
							(end -0.381 0.3683)
						)
						(arc
							(start -0.381 -0.3683)
							(mid -0.321484 -0.511984)
							(end -0.1778 -0.5715)
						)
						(arc
							(start 0.1778 -0.5715)
							(mid 0.321484 -0.511984)
							(end 0.381 -0.3683)
						)
						(arc
							(start 0.381 0.3683)
							(mid 0.321484 0.511984)
							(end 0.1778 0.5715)
						)
					)
					(width 0)
					(fill yes)
				)
			)
		)
		(pad "S" smd custom
			(at 0.98425 0.9525 90)
			(size 0.1905 0.1905)
			(layers "F.Cu" "F.Mask" "F.Paste")
			(net "P3V3_EN_R")
			(options
				(clearance outline)
				(anchor circle)
			)
			(primitives
				(gr_poly
					(pts
						(arc
							(start -0.1778 0.5715)
							(mid -0.321484 0.511984)
							(end -0.381 0.3683)
						)
						(arc
							(start -0.381 -0.3683)
							(mid -0.321484 -0.511984)
							(end -0.1778 -0.5715)
						)
						(arc
							(start 0.1778 -0.5715)
							(mid 0.321484 -0.511984)
							(end 0.381 -0.3683)
						)
						(arc
							(start 0.381 0.3683)
							(mid 0.321484 0.511984)
							(end 0.1778 0.5715)
						)
					)
					(width 0)
					(fill yes)
				)
			)
		)
	)
	(footprint ""
		(layer "F.Cu")
		(at 73.92797 -138.863324 -90)
		(property "Reference" "R51"
			(at 0 0 270)
			(layer "F.SilkS")
			(hide yes)
			(effects
				(font
					(size 1.27 1.27)
				)
			)
		)
		(property "Value" "33R2F-3-GP"
			(at 0.064008 -3.993896 270)
			(unlocked yes)
			(layer "F.Fab")
			(hide yes)
			(effects
				(font
					(size 1.016 1.016)
					(thickness 0.1524)
				)
			)
		)
		(property "Device Type" "R402H16"
			(at 0.064008 -5.517896 270)
			(unlocked yes)
			(layer "F.Fab")
			(hide yes)
			(effects
				(font
					(size 1.016 1.016)
					(thickness 0.1524)
				)
			)
		)
		(duplicate_pad_numbers_are_jumpers no)
		(fp_line
			(start -0.508 -0.9398)
			(end -0.508 0.9398)
			(stroke
				(width 0.1524)
				(type default)
			)
			(layer "F.SilkS")
		)
		(fp_line
			(start 0.508 -0.9398)
			(end -0.508 -0.9398)
			(stroke
				(width 0.1524)
				(type default)
			)
			(layer "F.SilkS")
		)
		(fp_rect
			(start -0.508 0.9398)
			(end 0.508 -0.9398)
			(stroke
				(width 0)
				(type default)
			)
			(fill no)
			(layer "F.CrtYd")
		)
		(fp_rect
			(start -0.508 0.9398)
			(end 0.508 -0.9398)
			(stroke
				(width 0)
				(type default)
			)
			(fill no)
			(layer "F.Fab")
		)
		(pad "1" smd custom
			(at 0 -0.4445 270)
			(size 0.1397 0.1397)
			(layers "F.Cu" "F.Mask" "F.Paste")
			(net "FP_PWR_BTN_N")
			(options
				(clearance outline)
				(anchor circle)
			)
			(primitives
				(gr_poly
					(pts
						(arc
							(start -0.1778 -0.2794)
							(mid -0.249642 -0.249642)
							(end -0.2794 -0.1778)
						)
						(arc
							(start -0.2794 0.1778)
							(mid -0.249642 0.249642)
							(end -0.1778 0.2794)
						)
						(arc
							(start 0.1778 0.2794)
							(mid 0.249642 0.249642)
							(end 0.2794 0.1778)
						)
						(arc
							(start 0.2794 -0.1778)
							(mid 0.249642 -0.249642)
							(end 0.1778 -0.2794)
						)
					)
					(width 0)
					(fill yes)
				)
			)
		)
		(pad "2" smd custom
			(at 0 0.4445 270)
			(size 0.1397 0.1397)
			(layers "F.Cu" "F.Mask" "F.Paste")
			(net "FP_PWR_BTN_N_R")
			(options
				(clearance outline)
				(anchor circle)
			)
			(primitives
				(gr_poly
					(pts
						(arc
							(start -0.1778 -0.2794)
							(mid -0.249642 -0.249642)
							(end -0.2794 -0.1778)
						)
						(arc
							(start -0.2794 0.1778)
							(mid -0.249642 0.249642)
							(end -0.1778 0.2794)
						)
						(arc
							(start 0.1778 0.2794)
							(mid 0.249642 0.249642)
							(end 0.2794 0.1778)
						)
						(arc
							(start 0.2794 -0.1778)
							(mid 0.249642 -0.249642)
							(end 0.1778 -0.2794)
						)
					)
					(width 0)
					(fill yes)
				)
			)
		)
	)
	(footprint ""
		(layer "F.Cu")
		(at 213.011258 -96.65081)
		(property "Reference" "R825"
			(at 0 0 0)
			(layer "F.SilkS")
			(hide yes)
			(effects
				(font
					(size 1.27 1.27)
				)
			)
		)
		(property "Value" "10KR2F-2-GP"
			(at 0.064008 -3.993896 0)
			(unlocked yes)
			(layer "F.Fab")
			(hide yes)
			(effects
				(font
					(size 1.016 1.016)
					(thickness 0.1524)
				)
			)
		)
		(property "Device Type" "R402H16"
			(at 0.064008 -5.517896 0)
			(unlocked yes)
			(layer "F.Fab")
			(hide yes)
			(effects
				(font
					(size 1.016 1.016)
					(thickness 0.1524)
				)
			)
		)
		(duplicate_pad_numbers_are_jumpers no)
		(fp_line
			(start -0.508 -0.9398)
			(end -0.508 0.9398)
			(stroke
				(width 0.1524)
				(type default)
			)
			(layer "F.SilkS")
		)
		(fp_line
			(start 0.508 -0.9398)
			(end -0.508 -0.9398)
			(stroke
				(width 0.1524)
				(type default)
			)
			(layer "F.SilkS")
		)
		(fp_rect
			(start -0.508 0.9398)
			(end 0.508 -0.9398)
			(stroke
				(width 0)
				(type default)
			)
			(fill no)
			(layer "F.CrtYd")
		)
		(fp_rect
			(start -0.508 0.9398)
			(end 0.508 -0.9398)
			(stroke
				(width 0)
				(type default)
			)
			(fill no)
			(layer "F.Fab")
		)
		(pad "1" smd custom
			(at 0 -0.4445)
			(size 0.1397 0.1397)
			(layers "F.Cu" "F.Mask" "F.Paste")
			(net "AGND_P3V3_M2")
			(options
				(clearance outline)
				(anchor circle)
			)
			(primitives
				(gr_poly
					(pts
						(arc
							(start -0.1778 -0.2794)
							(mid -0.249642 -0.249642)
							(end -0.2794 -0.1778)
						)
						(arc
							(start -0.2794 0.1778)
							(mid -0.249642 0.249642)
							(end -0.1778 0.2794)
						)
						(arc
							(start 0.1778 0.2794)
							(mid 0.249642 0.249642)
							(end 0.2794 0.1778)
						)
						(arc
							(start 0.2794 -0.1778)
							(mid 0.249642 -0.249642)
							(end 0.1778 -0.2794)
						)
					)
					(width 0)
					(fill yes)
				)
			)
		)
		(pad "2" smd custom
			(at 0 0.4445)
			(size 0.1397 0.1397)
			(layers "F.Cu" "F.Mask" "F.Paste")
			(net "P3V3_M2_VFB")
			(options
				(clearance outline)
				(anchor circle)
			)
			(primitives
				(gr_poly
					(pts
						(arc
							(start -0.1778 -0.2794)
							(mid -0.249642 -0.249642)
							(end -0.2794 -0.1778)
						)
						(arc
							(start -0.2794 0.1778)
							(mid -0.249642 0.249642)
							(end -0.1778 0.2794)
						)
						(arc
							(start 0.1778 0.2794)
							(mid 0.249642 0.249642)
							(end 0.2794 0.1778)
						)
						(arc
							(start 0.2794 -0.1778)
							(mid 0.249642 -0.249642)
							(end 0.1778 -0.2794)
						)
					)
					(width 0)
					(fill yes)
				)
			)
		)
	)
	(footprint ""
		(layer "F.Cu")
		(at 92.499942 -187.999878)
		(property "Reference" ""
			(at 0 0 0)
			(layer "F.SilkS")
			(hide yes)
			(effects
				(font
					(size 1.27 1.27)
				)
			)
		)
		(property "Value" "*"
			(at -6.38175 0.19685 0)
			(unlocked yes)
			(layer "F.Fab")
			(hide yes)
			(effects
				(font
					(size 1.016 1.016)
					(thickness 0.1524)
				)
			)
		)
		(duplicate_pad_numbers_are_jumpers no)
		(fp_poly
			(pts
				(arc
					(start 5.0673 0)
					(mid -5.0673 0)
					(end 5.0673 0)
				)
			)
			(stroke
				(width 0)
				(type default)
			)
			(fill no)
			(layer "B.CrtYd")
		)
		(fp_poly
			(pts
				(arc
					(start 5.0673 0)
					(mid -5.0673 0)
					(end 5.0673 0)
				)
			)
			(stroke
				(width 0)
				(type default)
			)
			(fill no)
			(layer "F.CrtYd")
		)
		(fp_poly
			(pts
				(arc
					(start 5.0673 0)
					(mid -5.0673 0)
					(end 5.0673 0)
				)
			)
			(stroke
				(width 0)
				(type default)
			)
			(fill no)
			(layer "B.Fab")
		)
		(fp_poly
			(pts
				(arc
					(start 5.0673 0)
					(mid -5.0673 0)
					(end 5.0673 0)
				)
			)
			(stroke
				(width 0)
				(type default)
			)
			(fill no)
			(layer "F.Fab")
		)
		(pad "1" thru_hole circle
			(at 0 0)
			(size 9.525 9.525)
			(drill 3.5052)
			(layers "*.Cu" "*.Mask")
			(remove_unused_layers no)
			(net "Net_33")
			(clearance -2.5019)
			(thermal_gap 0.3048)
			(padstack
				(mode front_inner_back)
				(layer "Inner"
					(shape circle)
					(size 3.9116 3.9116)
					(clearance 0.3048)
				)
				(layer "B.Cu"
					(shape circle)
					(size 9.525 9.525)
					(clearance -2.5019)
				)
			)
		)
	)
)
